FILE_TYPE = CONNECTIVITY;
{Allegro Design Entry HDL 16.6-p007 (v16-6-112F) 10/10/2012}
"PAGE_NUMBER" = 208;
0"NC";
1"GND\g";
2"GND\g";
3"PVCCIN_CPU1\g";
4"GND\g";
5"GND\g";
6"PVCCIN_CPU1\g";
7"GND\g";
8"VR_FET_SW_P12V_STBY_PVCCIN_CPU1\g";
9"GND\g";
10"VR_FET_SW_P12V_STBY_PVCCIN_CPU1\g";
11"GND\g";
12"P5V_STBY\g";
13"P5V_STBY\g";
14"GND\g";
15"GND\g";
16"GND\g";
17"PVCCIN_CPU1\g";
18"GND\g";
19"GND\g";
20"GND\g";
21"GND\g";
22"VR_PVCCIN_CPU1_AIREF4";
23"VR_PVCCIN_CPU1_AIREF3";
24"VR_PVCCIN_CPU1_PH3_BOOT_R";
25"VR_PVCCIN_CPU1_PHASE4"VOLTAGE"5";
26"VR_PVCCIN_CPU1_PHASE3"VOLTAGE"5";
27"VR_PVCCIN_CPU1_PH4_VCIN"VOLTAGE"5";
28"VR_PVCCIN_CPU1_PWM4";
29"VR_PVCCIN_CPU1_PH3_VCIN"VOLTAGE"5";
30"VR_PVCCIN_CPU1_PWM3";
31"VR_PVCCIN_CPU1_PH3_BOOT";
32"VR_PVCCIN_CPU1_PHASE4_RC";
33"VR_PVCCIN_CPU1_PHASE3_RC";
34"VR_PVCCIN_CPU1_PH4_PHASE"VOLTAGE"5";
35"VR_PVCCIN_CPU1_PH4_BOOT_R";
36"TP_PVCCIN_CPU1_PH4_GL_0";
37"VR_PVCCIN_CPU1_PH3_PHASE";
38"ISENSE_PVCCIN_CPU1_PH4_IMON";
39"VR_PVCCIN_CPU1_PH4_OCSET";
40"TP_PVCCIN_CPU1_PH3_GL_0";
41"TP_PVCCIN_CPU1_PH3_GL_1";
42"VR_PVCCIN_CPU1_PH4_BOOT";
43"A_TSENSE_PVCCIN_CPU1";
44"VR_PVCCIN_CPU1_PH3_OCSET";
45"ISENSE_PVCCIN_CPU1_PH3_IMON";
46"A_TSENSE_PVCCIN_CPU1";
47"TP_PVCCIN_CPU1_PH4_GL_1";
48"GND\g";
%"GND"
"1","(-400,3075)","0","mstr_symbols","I10";
;
ROOM"PVCCIN_CPU1_PWR_VR"
BOM_COST"PROC_VRD_VCCIN_CPU0"
SIZE"1B"
CDS_LIB"mstr_symbols"
VOLTAGE"0"
BODY_TYPE"PLUMBING"
HDL_POWER"GND";
"A\NAC"1;
%"CAP"
"1","(-2225,3500)","0","mstr_discrete","I104";
;
CDS_SEC"1"
CDS_LOCATION"CT18"
PART_NUMBER"A36096-046"
VALUE"1000PF"
VOLTAGE"50V"
TOLERANCE"10%"
POP"NOPOP"
PACK_TYPE"0402LF"
MATERIAL"X7R"
LOCATION"CT18"
CDS_LIB"mstr_discrete"
ROOM"VDDQ_KLM_PWR_VR"
SEC"1"
SEC_TYPE"0402LF";
"A"
$PN"1"26;
"B"
$PN"2"33;
%"CAP"
"1","(-2075,875)","0","mstr_discrete","I105";
;
CDS_SEC"1"
CDS_LOCATION"CT20"
POP"NOPOP"
TOLERANCE"10%"
PART_NUMBER"A36096-046"
MATERIAL"X7R"
LOCATION"CT20"
VALUE"1000PF"
VOLTAGE"50V"
PACK_TYPE"0402LF"
CDS_LIB"mstr_discrete"
ROOM"VDDQ_KLM_PWR_VR"
SEC"1"
SEC_TYPE"0402LF";
"A"
$PN"1"25;
"B"
$PN"2"32;
%"RES"
"1","(-4975,3700)","0","mstr_discrete","I108";
;
CDS_SEC"1"
CDS_LOCATION"RT11"
LOCATION"RT11"
VALUE"0"
MATERIAL"CHIP"
WATTAGE"1/10W"
PART_NUMBER"G22178-002"
TOLERANCE"5.0%"
PACK_TYPE"0603"
CDS_LIB"mstr_discrete"
ROOM"NIC_SPRV"
BOM_COST"NT_GBE_BASE"
SEC"1"
SEC_TYPE"0603";
"B"
$PN"2"24;
"A"
$PN"1"31;
%"RES"
"1","(-4975,1075)","0","mstr_discrete","I109";
;
CDS_SEC"1"
CDS_LOCATION"RT14"
MATERIAL"CHIP"
TOLERANCE"5.0%"
PACK_TYPE"0603"
LOCATION"RT14"
VALUE"0"
WATTAGE"1/10W"
PART_NUMBER"G22178-002"
CDS_LIB"mstr_discrete"
ROOM"NIC_SPRV"
BOM_COST"NT_GBE_BASE"
SEC"1"
SEC_TYPE"0603";
"B"
$PN"2"35;
"A"
$PN"1"42;
%"RES"
"1","(-5350,4700)","0","mstr_discrete","I114";
;
PART_NUMBER"G21497-005"
MATERIAL"CHIP"
TOLERANCE"5%"
PACK_TYPE"0402"
WATTAGE"1/16W"
LOCATION"R9P22"
VALUE"0.0"
CDS_LOCATION"R9P22"
BOM_COST"PROC_SIDEBAND"
CDS_LIB"mstr_discrete"
SEC_TYPE"0402"
SEC"1"
ROOM"CPU0"
CDS_SEC"1";
"B"
$PN"2"12;
"A"
$PN"1"29;
%"RES"
"1","(-5450,2025)","0","mstr_discrete","I115";
;
PACK_TYPE"0402"
VALUE"0.0"
WATTAGE"1/16W"
TOLERANCE"5%"
LOCATION"R9P8"
PART_NUMBER"G21497-005"
MATERIAL"CHIP"
BOM_COST"PROC_SIDEBAND"
CDS_LIB"mstr_discrete"
SEC_TYPE"0402"
SEC"1"
ROOM"CPU0"
CDS_SEC"1"
CDS_LOCATION"R9P8";
"B"
$PN"2"13;
"A"
$PN"1"27;
%"IND-120NH-30-GP"
"1","(-1425,3650)","1","w_hdl","I116";
;
CDS_SEC"1"
CDS_LOCATION"L1D2"
VALUE"IND-120NH-30-GP"
LOCATION"L1D2"
ATTRIBUTE"120NH"
RATED"ISAT=94A@25C"
PACK_SIZE"DCR=0.17MOHM"
TYPE"IRMS=66A@DELTA_T<40C"
PACK_TYPE"DISCRET-GB2"
SEC"1"
SEC_TYPE"DISCRET-GB2"
CDS_LMAN_SYM_OUTLINE"-75,100,75,-100"
CDS_LIB"w_hdl"
PART_NUMBER"068.1202N.M001";
"F"
$PN"2"17;
"S"
$PN"1"26;
%"IND-120NH-30-GP"
"1","(-1275,1050)","1","w_hdl","I117";
;
CDS_SEC"1"
CDS_LOCATION"L1D1"
LOCATION"L1D1"
VALUE"IND-120NH-30-GP"
ATTRIBUTE"120NH"
RATED"ISAT=94A@25C"
PACK_SIZE"DCR=0.17MOHM"
TYPE"IRMS=66A@DELTA_T<40C"
PACK_TYPE"DISCRET-GB2"
SEC"1"
SEC_TYPE"DISCRET-GB2"
CDS_LMAN_SYM_OUTLINE"-75,100,75,-100"
CDS_LIB"w_hdl"
PART_NUMBER"068.1202N.M001";
"F"
$PN"2"3;
"S"
$PN"1"25;
%"SC1U10V2KX-4-GP"
"1","(-5100,4200)","0","w_hdl","I118";
;
CDS_SEC"1"
CDS_LOCATION"C1D15"
TOLERANCE"10%"
RATED"10V"
PACK_SIZE"0402"
VALUE"SC1U10V2KX-4-GP"
ATTRIBUTE"1UF"
LOCATION"C1D15"
PART_NUMBER"78.10523.8FL"
CDS_LIB"w_hdl"
CDS_LMAN_SYM_OUTLINE"-50,25,50,-25"
SEC_TYPE"SMD-BCG6"
SEC"1"
PACK_TYPE"SMD-BCG6";
"2"
$PN"2"9;
"1"
$PN"1"12;
%"SC1U10V2KX-4-GP"
"1","(-5200,1550)","0","w_hdl","I119";
;
CDS_SEC"1"
CDS_LOCATION"C1D5"
LOCATION"C1D5"
VALUE"SC1U10V2KX-4-GP"
ATTRIBUTE"1UF"
TOLERANCE"10%"
RATED"10V"
PACK_SIZE"0402"
PART_NUMBER"78.10523.8FL"
CDS_LIB"w_hdl"
CDS_LMAN_SYM_OUTLINE"-50,25,50,-25"
SEC_TYPE"SMD-BCG6"
SEC"1"
PACK_TYPE"SMD-BCG6";
"2"
$PN"2"11;
"1"
$PN"1"13;
%"CAPP"
"1","(-1450,2650)","0","mstr_discrete","I12";
;
CDS_SEC"1"
LOCATION"C9P8"
TOLERANCE"20%"
VALUE"470UF"
PACK_TYPE"3018"
PART_NUMBER"699013-049"
VOLTAGE"2.5V"
MATERIAL"ALUM"
GROUP"PWR_BULK_CAP"
CDS_LIB"mstr_discrete"
ROOM"PVCCIN_CPU1_DECAP_VR"
CDS_LOCATION"C9P8"
BOM_COST"PROC_VRD_VCCIN_CPU0"
SEC"1"
SEC_TYPE"3018";
"B"
$PN"2"2;
"A"
$PN"1"6;
%"1R3F-GP"
"1","(-2225,3175)","0","w_hdl","I120";
;
CDS_SEC"1"
CDS_LOCATION"RT12"
PACK_SIZE"0603"
RATED"1/10W"
LOCATION"RT12"
ATTRIBUTE"1 OHM"
VALUE"1R3F-GP"
POP"NOPOP"
TOLERANCE"1%"
CDS_LMAN_SYM_OUTLINE"-50,75,50,-75"
CDS_LIB"w_hdl"
PART_NUMBER"64.1R005.55L"
SEC_TYPE"RCL_GP"
SEC"1"
PACK_TYPE"RCL_GP";
"2"
$PN"2"19;
"1"
$PN"1"33;
%"1R3F-GP"
"1","(-2075,550)","0","w_hdl","I121";
;
CDS_SEC"1"
CDS_LOCATION"RT13"
PACK_SIZE"0603"
RATED"1/10W"
LOCATION"RT13"
VALUE"1R3F-GP"
ATTRIBUTE"1 OHM"
POP"NOPOP"
TOLERANCE"1%"
PACK_TYPE"RCL_GP"
SEC"1"
SEC_TYPE"RCL_GP"
PART_NUMBER"64.1R005.55L"
CDS_LIB"w_hdl"
CDS_LMAN_SYM_OUTLINE"-50,75,50,-75";
"2"
$PN"2"48;
"1"
$PN"1"32;
%"GND"
"1","(-1000,2275)","0","mstr_symbols","I13";
;
HDL_POWER"GND"
BODY_TYPE"PLUMBING"
VOLTAGE"0"
CDS_LIB"mstr_symbols"
SIZE"1B"
BOM_COST"PROC_VRD_VCCIN_CPU0"
ROOM"PVCCIN_CPU1_DECAP_VR";
"A\NAC"2;
%"CAPP"
"1","(-1925,2650)","0","mstr_discrete","I14";
;
CDS_SEC"1"
MATERIAL"ALUM"
VALUE"470UF"
TOLERANCE"20%"
LOCATION"C9P5"
PART_NUMBER"699013-049"
PACK_TYPE"3018"
GROUP"PWR_BULK_CAP"
VOLTAGE"2.5V"
CDS_LIB"mstr_discrete"
ROOM"PVCCIN_CPU1_DECAP_VR"
CDS_LOCATION"C9P5"
BOM_COST"PROC_VRD_VCCIN_CPU0"
SEC"1"
SEC_TYPE"3018";
"B"
$PN"2"2;
"A"
$PN"1"6;
%"PVCCIN_CPU1"
"1","(-350,1125)","0","mstr_symbols","I18";
;
HDL_POWER"PVCCIN_CPU1"
BODY_TYPE"PLUMBING"
VOLTAGE"2.0V"
CDS_LIB"mstr_symbols";
"G\NAC"3;
%"GND"
"1","(-350,450)","0","mstr_symbols","I21";
;
HDL_POWER"GND"
BODY_TYPE"PLUMBING"
VOLTAGE"0"
SIZE"1B"
CDS_LIB"mstr_symbols"
BOM_COST"PROC_VRD_VCCIN_CPU0"
ROOM"PVCCIN_CPU1_PWR_VR";
"A\NAC"4;
%"CAP_A"
"1","(-700,800)","0","dev_discrete","I22";
;
LOCATION"C1D3"
VALUE"22.0UF"
PACK_TYPE"0603V"
PART_NUMBER"E15431-004"
VOLTAGE"4V"
TOLERANCE"20%"
MATERIAL"X6S"
GROUP"PWR_MLCC_CAP"
SEC_TYPE"0603V"
SEC"1"
BOM_COST"PROC_VRD_VCCIN_CPU0"
CDS_LOCATION"C1D3"
CDS_SEC"1"
ROOM"PVCCIN_CPU1_PWR_VR"
CDS_LIB"dev_discrete";
"B"
$PN"2"4;
"A"
$PN"1"3;
%"GND"
"1","(-2600,3175)","0","mstr_symbols","I23";
;
HDL_POWER"GND"
BODY_TYPE"PLUMBING"
SIZE"1B"
VOLTAGE"0"
CDS_LIB"mstr_symbols"
BOM_COST"PROC_VRD_VCCIN_CPU0"
ROOM"PVCCIN_CPU1_PWR_VR";
"A\NAC"5;
%"CAPP"
"1","(-2375,2650)","0","mstr_discrete","I24";
;
CDS_SEC"1"
MATERIAL"ALUM"
PART_NUMBER"699013-049"
VOLTAGE"2.5V"
TOLERANCE"20%"
VALUE"470UF"
LOCATION"C9N24"
PACK_TYPE"3018"
GROUP"PWR_BULK_CAP"
CDS_LIB"mstr_discrete"
ROOM"PVCCIN_CPU1_DECAP_VR"
CDS_LOCATION"C9N24"
BOM_COST"PROC_VRD_VCCIN_CPU0"
SEC"1"
SEC_TYPE"3018";
"B"
$PN"2"2;
"A"
$PN"1"6;
%"CAPP"
"1","(-2825,2650)","0","mstr_discrete","I25";
;
CDS_SEC"1"
PART_NUMBER"699013-049"
VALUE"470UF"
VOLTAGE"2.5V"
LOCATION"C9R9"
TOLERANCE"20%"
MATERIAL"ALUM"
PACK_TYPE"3018"
GROUP"PWR_BULK_CAP"
CDS_LIB"mstr_discrete"
CDS_LOCATION"C9R9"
ROOM"PVCCIN_CPU1_DECAP_VR"
BOM_COST"PROC_VRD_VCCIN_CPU0"
SEC_TYPE"3018"
SEC"1";
"B"
$PN"2"2;
"A"
$PN"1"6;
%"CAPP"
"1","(-3275,2650)","0","mstr_discrete","I26";
;
CDS_SEC"1"
PART_NUMBER"699013-049"
LOCATION"C9R3"
PACK_TYPE"3018"
MATERIAL"ALUM"
VOLTAGE"2.5V"
VALUE"470UF"
TOLERANCE"20%"
GROUP"PWR_BULK_CAP"
CDS_LIB"mstr_discrete"
ROOM"PVCCIN_CPU1_DECAP_VR"
CDS_LOCATION"C9R3"
BOM_COST"PROC_VRD_VCCIN_CPU0"
SEC"1"
SEC_TYPE"3018";
"B"
$PN"2"2;
"A"
$PN"1"6;
%"IR354XX"
"1","(-3300,3875)","0","mstr_discrete","I27";
;
CDS_SEC"1"
PART_NUMBER"H73688-001"
MATERIAL"IC"
LOCATION"EU1D3"
SEC"1"
SEC_TYPE"SM"
CDS_LOCATION"EU1D3"
PACK_TYPE"SM"
CDS_LIB"mstr_discrete"
ROOM"PVCCIN_CPU1_PWR_VR"
VALUE"IR35411";
"TOUT_FLT"
$PN"36"43;
"NC"
$PN"31"0;
"OCSET"
$PN"37"44;
"IOUT"
$PN"38"45;
"SW"
$PN"10"26;
"BOOST"
$PN"33"24;
"REFIN"
$PN"39"23;
"PWM"
$PN"34"30;
"PHASE"
$PN"32"37;
"VIN<0>"
$PN"25"8;
"VCC"
$PN"3"29;
"VIN<1>"
$PN"30"8;
"EN"
$PN"35"12;
"VDRV"
$PN"4"12;
"VOS"
$PN"1"17;
"LGND"
$PN"2"5;
"PGND<1>"
$PN"7"5;
"PGND<2>"
$PN"40"5;
"PGND<0>"
$PN"5"5;
"GL<0>"
$PN"6"40;
"GL<1>"
$PN"41"41;
%"CAPP"
"1","(-3725,2650)","0","mstr_discrete","I28";
;
CDS_SEC"1"
TOLERANCE"20%"
VOLTAGE"2.5V"
VALUE"470UF"
LOCATION"C9P23"
PART_NUMBER"699013-049"
PACK_TYPE"3018"
MATERIAL"ALUM"
GROUP"PWR_BULK_CAP"
CDS_LIB"mstr_discrete"
ROOM"PVCCIN_CPU1_DECAP_VR"
CDS_LOCATION"C9P23"
BOM_COST"PROC_VRD_VCCIN_CPU0"
SEC"1"
SEC_TYPE"3018";
"B"
$PN"2"2;
"A"
$PN"1"6;
%"PVCCIN_CPU1"
"1","(-4250,2900)","0","mstr_symbols","I29";
;
HDL_POWER"PVCCIN_CPU1"
BODY_TYPE"PLUMBING"
CDS_LIB"mstr_symbols"
VOLTAGE"2.0V";
"G\NAC"6;
%"CAPP"
"1","(-4250,2650)","0","mstr_discrete","I30";
;
CDS_SEC"1"
VOLTAGE"2.5V"
TOLERANCE"20%"
VALUE"470UF"
LOCATION"C9P18"
MATERIAL"ALUM"
PACK_TYPE"3018"
PART_NUMBER"699013-049"
GROUP"PWR_BULK_CAP"
SEC_TYPE"3018"
SEC"1"
BOM_COST"PROC_VRD_VCCIN_CPU0"
CDS_LOCATION"C9P18"
ROOM"PVCCIN_CPU1_DECAP_VR"
CDS_LIB"mstr_discrete";
"B"
$PN"2"2;
"A"
$PN"1"6;
%"GND"
"1","(-2575,600)","0","mstr_symbols","I33";
;
HDL_POWER"GND"
BODY_TYPE"PLUMBING"
SIZE"1B"
VOLTAGE"0"
CDS_LIB"mstr_symbols"
BOM_COST"PROC_VRD_VCCIN_CPU0"
ROOM"PVCCIN_CPU1_PWR_VR";
"A\NAC"7;
%"VCC_CORE"
"1","(-6625,4575)","0","mstr_symbols","I37";
;
HDL_POWER"VR_FET_SW_P12V_STBY_PVCCIN_CPU1"
CDS_LIB"mstr_symbols";
"A"8;
%"CAP"
"1","(-4775,4200)","0","mstr_discrete","I38";
;
CDS_SEC"1"
PART_NUMBER"A36096-155"
PACK_TYPE"0402"
TOLERANCE"10%"
MATERIAL"X7R"
LOCATION"C1D16"
VALUE"0.22UF"
VOLTAGE"16V"
CDS_LIB"mstr_discrete"
CDS_LOCATION"C1D16"
ROOM"PVCCIN_CPU1_PWR_VR"
SEC_TYPE"0402"
SEC"1";
"A"
$PN"1"12;
"B"
$PN"2"9;
%"CAP"
"1","(-5975,3575)","2","mstr_discrete","I40";
;
CDS_SEC"1"
LOCATION"C1D20"
VALUE"0.220UF"
VOLTAGE"16V"
MATERIAL"X7R"
PART_NUMBER"A36096-104"
PACK_TYPE"0402"
TOLERANCE"10%"
CDS_LIB"mstr_discrete"
SEC_TYPE"0402"
SPOF"TRUE"
SEC"1"
CDS_LOCATION"C1D20"
NO_XNET_CONNECTION"1"
ROOM"PVCCIN_CPU1_PWR_VR";
"A"
$PN"1"31;
"B"
$PN"2"37;
%"CAP"
"1","(-5500,4150)","0","mstr_discrete","I43";
;
CDS_SEC"1"
VALUE"1.0UF"
VOLTAGE"16V"
TOLERANCE"10%"
MATERIAL"X6S"
PACK_TYPE"0402"
PART_NUMBER"D97712-011"
LOCATION"C1D17"
CDS_LOCATION"C1D17"
CDS_LIB"mstr_discrete"
ROOM"PVCCIN_CPU1_PWR_VR"
SEC"1"
SEC_TYPE"0402";
"A"
$PN"1"29;
"B"
$PN"2"9;
%"CAP_A"
"1","(-5775,4150)","0","dev_discrete","I44";
;
VOLTAGE"16V"
LOCATION"C1D28"
VALUE"0.1UF"
PACK_TYPE"0402V"
PART_NUMBER"A36096-030"
MATERIAL"X7R"
TOLERANCE"10%"
CDS_LOCATION"C1D28"
CDS_LIB"dev_discrete"
CDS_SEC"1"
ROOM"PVCCIN_CPU1_PWR_VR"
SEC_TYPE"0402V"
SEC"1";
"B"
$PN"2"9;
"A"
$PN"1"8;
%"CAP"
"1","(-6025,4150)","0","mstr_discrete","I45";
;
CDS_SEC"1"
MATERIAL"X6S"
VOLTAGE"16V"
TOLERANCE"10%"
VALUE"1.0UF"
LOCATION"C1D23"
PART_NUMBER"D97712-011"
PACK_TYPE"0402"
CDS_LIB"mstr_discrete"
CDS_LOCATION"C1D23"
SEC_TYPE"0402"
SEC"1"
ROOM"PVCCIN_CPU1_PWR_VR";
"A"
$PN"1"8;
"B"
$PN"2"9;
%"CAP"
"1","(-4800,1575)","0","mstr_discrete","I46";
;
CDS_SEC"1"
VOLTAGE"16V"
TOLERANCE"10%"
MATERIAL"X7R"
PART_NUMBER"A36096-155"
PACK_TYPE"0402"
VALUE"0.22UF"
LOCATION"C1D6"
CDS_LIB"mstr_discrete"
ROOM"PVCCIN_CPU1_PWR_VR"
CDS_LOCATION"C1D6"
SEC"1"
SEC_TYPE"0402";
"A"
$PN"1"13;
"B"
$PN"2"11;
%"CAP"
"1","(-5975,900)","2","mstr_discrete","I48";
;
CDS_SEC"1"
PACK_TYPE"0402"
PART_NUMBER"A36096-104"
VALUE"0.220UF"
TOLERANCE"10%"
MATERIAL"X7R"
VOLTAGE"16V"
LOCATION"C1D10"
SPOF"TRUE"
SEC_TYPE"0402"
SEC"1"
CDS_LOCATION"C1D10"
NO_XNET_CONNECTION"1"
ROOM"PVCCIN_CPU1_PWR_VR"
CDS_LIB"mstr_discrete";
"A"
$PN"1"42;
"B"
$PN"2"34;
%"CAP"
"1","(-5700,1575)","0","mstr_discrete","I50";
;
CDS_SEC"1"
PACK_TYPE"0402"
MATERIAL"X6S"
TOLERANCE"10%"
VOLTAGE"16V"
PART_NUMBER"D97712-011"
VALUE"1.0UF"
LOCATION"C1D7"
CDS_LIB"mstr_discrete"
CDS_LOCATION"C1D7"
ROOM"PVCCIN_CPU1_PWR_VR"
SEC_TYPE"0402"
SEC"1";
"A"
$PN"1"27;
"B"
$PN"2"11;
%"CAP_A"
"1","(-5950,1575)","0","dev_discrete","I51";
;
VOLTAGE"16V"
PACK_TYPE"0402V"
TOLERANCE"10%"
MATERIAL"X7R"
PART_NUMBER"A36096-030"
VALUE"0.1UF"
LOCATION"C1D13"
SEC"1"
SEC_TYPE"0402V"
CDS_SEC"1"
CDS_LOCATION"C1D13"
ROOM"PVCCIN_CPU1_PWR_VR"
CDS_LIB"dev_discrete";
"B"
$PN"2"11;
"A"
$PN"1"10;
%"CAP"
"1","(-6250,1575)","0","mstr_discrete","I52";
;
CDS_SEC"1"
LOCATION"C1D12"
VALUE"1.0UF"
PACK_TYPE"0402"
VOLTAGE"16V"
MATERIAL"X6S"
TOLERANCE"10%"
PART_NUMBER"D97712-011"
SEC_TYPE"0402"
SEC"1"
CDS_LOCATION"C1D12"
ROOM"PVCCIN_CPU1_PWR_VR"
CDS_LIB"mstr_discrete";
"A"
$PN"1"10;
"B"
$PN"2"11;
%"CAP"
"1","(-6275,4150)","0","mstr_discrete","I53";
;
CDS_SEC"1"
MATERIAL"X6S"
PART_NUMBER"C95333-007"
LOCATION"C9P4"
VALUE"10UF"
TOLERANCE"10%"
VOLTAGE"16V"
PACK_TYPE"0805"
CDS_LIB"mstr_discrete"
CDS_LOCATION"C9P4"
SEC_TYPE"0805"
SEC"1"
ROOM"PVCCIN_CPU1_PWR_VR";
"A"
$PN"1"8;
"B"
$PN"2"9;
%"CAP"
"1","(-6550,4150)","0","mstr_discrete","I54";
;
CDS_SEC"1"
MATERIAL"X6S"
PACK_TYPE"0805"
VOLTAGE"16V"
TOLERANCE"10%"
VALUE"10UF"
LOCATION"C9P7"
PART_NUMBER"C95333-007"
CDS_LIB"mstr_discrete"
CDS_LOCATION"C9P7"
SEC_TYPE"0805"
SEC"1"
ROOM"PVCCIN_CPU1_PWR_VR";
"A"
$PN"1"8;
"B"
$PN"2"9;
%"CAP"
"1","(-6875,4150)","0","mstr_discrete","I55";
;
CDS_SEC"1"
PART_NUMBER"C95333-007"
PACK_TYPE"0805"
MATERIAL"X6S"
VALUE"10UF"
LOCATION"C9P9"
VOLTAGE"16V"
TOLERANCE"10%"
CDS_LIB"mstr_discrete"
CDS_LOCATION"C9P9"
ROOM"PVCCIN_CPU1_PWR_VR"
SEC"1"
SEC_TYPE"0805";
"A"
$PN"1"8;
"B"
$PN"2"9;
%"GND"
"1","(-6875,3650)","0","mstr_symbols","I57";
;
HDL_POWER"GND"
BODY_TYPE"PLUMBING"
ROOM"PVCCIN_CPU1_PWR_VR"
BOM_COST"PROC_VRD_VCCIN_CPU0"
VOLTAGE"0"
CDS_LIB"mstr_symbols"
SIZE"1B";
"A\NAC"9;
%"CAP"
"1","(-6500,1575)","0","mstr_discrete","I58";
;
CDS_SEC"1"
CDS_LOCATION"C9P24"
PACK_TYPE"0805"
VOLTAGE"16V"
TOLERANCE"10%"
VALUE"10UF"
LOCATION"C9P24"
MATERIAL"X6S"
PART_NUMBER"C95333-007"
CDS_LIB"mstr_discrete"
SEC_TYPE"0805"
SEC"1"
ROOM"PVCCIN_CPU1_PWR_VR";
"A"
$PN"1"10;
"B"
$PN"2"11;
%"CAP"
"1","(-6800,1575)","0","mstr_discrete","I59";
;
CDS_SEC"1"
LOCATION"C9P1"
VALUE"10UF"
VOLTAGE"16V"
TOLERANCE"10%"
PART_NUMBER"C95333-007"
PACK_TYPE"0805"
MATERIAL"X6S"
ROOM"PVCCIN_CPU1_PWR_VR"
CDS_LOCATION"C9P1"
SEC"1"
SEC_TYPE"0805"
CDS_LIB"mstr_discrete";
"A"
$PN"1"10;
"B"
$PN"2"11;
%"CAP"
"1","(-7050,1575)","0","mstr_discrete","I60";
;
CDS_SEC"1"
PART_NUMBER"C95333-007"
VALUE"10UF"
MATERIAL"X6S"
VOLTAGE"16V"
TOLERANCE"10%"
LOCATION"C9P2"
PACK_TYPE"0805"
CDS_LIB"mstr_discrete"
SEC_TYPE"0805"
SEC"1"
ROOM"PVCCIN_CPU1_PWR_VR"
CDS_LOCATION"C9P2";
"A"
$PN"1"10;
"B"
$PN"2"11;
%"VCC_CORE"
"1","(-6475,1975)","0","mstr_symbols","I62";
;
HDL_POWER"VR_FET_SW_P12V_STBY_PVCCIN_CPU1"
CDS_LIB"mstr_symbols";
"A"10;
%"GND"
"1","(-7050,950)","0","mstr_symbols","I63";
;
BOM_COST"PROC_VRD_VCCIN_CPU0"
ROOM"PVCCIN_CPU1_PWR_VR"
VOLTAGE"0"
CDS_LIB"mstr_symbols"
SIZE"1B"
BODY_TYPE"PLUMBING"
HDL_POWER"GND";
"A\NAC"11;
%"P5V_STBY"
"1","(-4925,4850)","0","mstr_symbols","I64";
;
HDL_POWER"P5V_STBY"
BODY_TYPE"PLUMBING"
SIZE"1B"
CDS_LIB"mstr_symbols"
VOLTAGE"5.0V";
"G\NAC"12;
%"P5V_STBY"
"1","(-5000,2150)","0","mstr_symbols","I65";
;
HDL_POWER"P5V_STBY"
BODY_TYPE"PLUMBING"
VOLTAGE"5.0V"
SIZE"1B"
CDS_LIB"mstr_symbols";
"G\NAC"13;
%"CAP_A"
"1","(-400,3400)","0","dev_discrete","I66";
;
MATERIAL"X6S"
TOLERANCE"20%"
VOLTAGE"4V"
VALUE"22.0UF"
LOCATION"C9P10"
PACK_TYPE"0603V"
PART_NUMBER"E15431-004"
GROUP"PWR_MLCC_CAP"
SEC_TYPE"0603V"
SEC"1"
CDS_SEC"1"
CDS_LOCATION"C9P10"
CDS_LIB"dev_discrete";
"B"
$PN"2"1;
"A"
$PN"1"17;
%"CAP_A"
"1","(-350,800)","0","dev_discrete","I67";
;
VALUE"22.0UF"
VOLTAGE"4V"
TOLERANCE"20%"
MATERIAL"X6S"
PART_NUMBER"E15431-004"
PACK_TYPE"0603V"
GROUP"PWR_MLCC_CAP"
LOCATION"C9R2"
SEC_TYPE"0603V"
SEC"1"
CDS_SEC"1"
CDS_LOCATION"C9R2"
CDS_LIB"dev_discrete";
"B"
$PN"2"4;
"A"
$PN"1"3;
%"RES"
"2","(-1000,2575)","0","mstr_discrete","I7";
;
CDS_SEC"1"
PACK_TYPE"0603"
TOLERANCE"1%"
VALUE"100.0"
PART_NUMBER"G22026-038"
MATERIAL"CHIP"
WATTAGE"1/10W"
LOCATION"R1E3"
SEC_TYPE"0603"
SEC"1"
BOM_COST"PROC_VRD_VCCIN_CPU0"
CDS_LOCATION"R1E3"
ROOM"PVCCIN_CPU1_DECAP_VR"
CDS_LIB"mstr_discrete";
"A"
$PN"1"6;
"B"
$PN"2"2;
%"IR354XX"
"1","(-3250,1275)","0","mstr_discrete","I71";
;
CDS_SEC"1"
PART_NUMBER"H73688-001"
MATERIAL"IC"
LOCATION"EU1D1"
SEC_TYPE"SM"
SEC"1"
PACK_TYPE"SM"
ROOM"PVCCIN_CPU1_PWR_VR"
CDS_LIB"mstr_discrete"
CDS_LOCATION"EU1D1"
VALUE"IR35411";
"TOUT_FLT"
$PN"36"46;
"NC"
$PN"31"0;
"OCSET"
$PN"37"39;
"IOUT"
$PN"38"38;
"SW"
$PN"10"25;
"BOOST"
$PN"33"35;
"REFIN"
$PN"39"22;
"PWM"
$PN"34"28;
"PHASE"
$PN"32"34;
"VIN<0>"
$PN"25"10;
"VCC"
$PN"3"27;
"VIN<1>"
$PN"30"10;
"EN"
$PN"35"13;
"VDRV"
$PN"4"13;
"VOS"
$PN"1"3;
"LGND"
$PN"2"7;
"PGND<1>"
$PN"7"7;
"PGND<2>"
$PN"40"7;
"PGND<0>"
$PN"5"7;
"GL<0>"
$PN"6"36;
"GL<1>"
$PN"41"47;
%"RES"
"2","(-625,1450)","0","mstr_discrete","I75";
;
CDS_LOCATION"R1D54"
LOCATION"R1D54"
TOLERANCE"1%"
VALUE"68.1K"
PACK_TYPE"0402"
WATTAGE"1/16W"
PART_NUMBER"G21796-187"
MATERIAL"EMPTY"
$SEC"1"
CDS_SEC"1"
CDS_LIB"mstr_discrete";
"A"
$PN"1"39;
"B"
$PN"2"15;
%"RES"
"2","(-700,4075)","0","mstr_discrete","I76";
;
CDS_LOCATION"R1D55"
LOCATION"R1D55"
PACK_TYPE"0402"
VALUE"68.1K"
TOLERANCE"1%"
WATTAGE"1/16W"
MATERIAL"EMPTY"
PART_NUMBER"G21796-187"
CDS_SEC"1"
$SEC"1"
CDS_LIB"mstr_discrete";
"A"
$PN"1"44;
"B"
$PN"2"14;
%"GND"
"1","(-700,3900)","0","mstr_symbols","I77";
;
ROOM"PVCCIN_CPU1_PWR_VR"
BOM_COST"PROC_VRD_VCCIN_CPU0"
SIZE"1B"
CDS_LIB"mstr_symbols"
VOLTAGE"0"
BODY_TYPE"PLUMBING"
HDL_POWER"GND";
"A\NAC"14;
%"GND"
"1","(-625,1225)","0","mstr_symbols","I78";
;
HDL_POWER"GND"
BODY_TYPE"PLUMBING"
VOLTAGE"0"
SIZE"1B"
CDS_LIB"mstr_symbols"
BOM_COST"PROC_VRD_VCCIN_CPU0"
ROOM"PVCCIN_CPU1_PWR_VR";
"A\NAC"15;
%"GND"
"1","(-3975,3125)","0","mstr_symbols","I79";
;
HDL_POWER"GND"
BODY_TYPE"PLUMBING"
ROOM"PVCCIN_CPU0_PWR_VR"
BOM_COST"PROC_VRD_VCCIN_CPU0"
SIZE"1B"
VOLTAGE"0"
CDS_LIB"mstr_symbols";
"A\NAC"16;
%"PVCCIN_CPU1"
"1","(-400,3700)","0","mstr_symbols","I8";
;
HDL_POWER"PVCCIN_CPU1"
BODY_TYPE"PLUMBING"
CDS_LIB"mstr_symbols"
VOLTAGE"2.0V";
"G\NAC"17;
%"CAP_A"
"1","(-3975,3375)","0","dev_discrete","I80";
;
CDS_SEC"1"
CDS_LOCATION"CT16"
POP"NOPOP"
PACK_TYPE"0402V"
PART_NUMBER"A36096-030"
MATERIAL"X7R"
TOLERANCE"10%"
VOLTAGE"16V"
VALUE"0.1UF"
LOCATION"CT16"
ROOM"PVCCIN_CPU0_PWR_VR"
CDS_LIB"dev_discrete"
SEC"1"
SEC_TYPE"0402V";
"B"
$PN"2"16;
"A"
$PN"1"23;
%"CAP"
"1","(-2050,3900)","0","mstr_discrete","I82";
;
CDS_SEC"1"
CDS_LOCATION"CTI7"
LOCATION"CTI7"
VOLTAGE"50V"
TOLERANCE"10%"
MATERIAL"X7R"
POP"NOPOP"
VALUE"1000PF"
PART_NUMBER"A36096-046"
PACK_TYPE"0402LF"
ROOM"VDDQ_KLM_PWR_VR"
CDS_LIB"mstr_discrete"
SEC"1"
SEC_TYPE"0402LF";
"A"
$PN"1"43;
"B"
$PN"2"18;
%"GND"
"1","(-2050,3700)","0","mstr_symbols","I83";
;
HDL_POWER"GND"
BODY_TYPE"PLUMBING"
SIZE"1B"
VOLTAGE"0"
ROOM"VDDQ_KLM_PWR_VR"
CDS_LIB"mstr_symbols";
"A\NAC"18;
%"GND"
"1","(-2225,2975)","0","mstr_symbols","I85";
;
HDL_POWER"GND"
BODY_TYPE"PLUMBING"
SIZE"1B"
VOLTAGE"0"
BOM_COST"PROC_VRD_VCCIN_CPU0"
ROOM"PVCCIN_CPU0_PWR_VR"
CDS_LIB"mstr_symbols";
"A\NAC"19;
%"CAP_A"
"1","(-3850,775)","0","dev_discrete","I87";
;
CDS_SEC"1"
CDS_LOCATION"CT21"
VALUE"0.1UF"
MATERIAL"X7R"
VOLTAGE"16V"
PACK_TYPE"0402V"
POP"NOPOP"
PART_NUMBER"A36096-030"
TOLERANCE"10%"
LOCATION"CT21"
CDS_LIB"dev_discrete"
ROOM"PVCCIN_CPU0_PWR_VR"
SEC"1"
SEC_TYPE"0402V";
"B"
$PN"2"20;
"A"
$PN"1"22;
%"GND"
"1","(-3850,525)","0","mstr_symbols","I88";
;
HDL_POWER"GND"
BODY_TYPE"PLUMBING"
CDS_LIB"mstr_symbols"
VOLTAGE"0"
SIZE"1B"
BOM_COST"PROC_VRD_VCCIN_CPU0"
ROOM"PVCCIN_CPU0_PWR_VR";
"A\NAC"20;
%"CAP_A"
"1","(-800,3400)","0","dev_discrete","I9";
;
LOCATION"C1D14"
VALUE"22.0UF"
VOLTAGE"4V"
TOLERANCE"20%"
PACK_TYPE"0603V"
PART_NUMBER"E15431-004"
MATERIAL"X6S"
GROUP"PWR_MLCC_CAP"
CDS_LIB"dev_discrete"
CDS_LOCATION"C1D14"
ROOM"PVCCIN_CPU1_PWR_VR"
CDS_SEC"1"
BOM_COST"PROC_VRD_VCCIN_CPU0"
SEC"1"
SEC_TYPE"0603V";
"B"
$PN"2"1;
"A"
$PN"1"17;
%"CAP"
"1","(-2000,1300)","0","mstr_discrete","I90";
;
CDS_SEC"1"
CDS_LOCATION"CT19"
POP"NOPOP"
VALUE"1000PF"
LOCATION"CT19"
VOLTAGE"50V"
TOLERANCE"10%"
MATERIAL"X7R"
PART_NUMBER"A36096-046"
PACK_TYPE"0402LF"
CDS_LIB"mstr_discrete"
ROOM"VDDQ_KLM_PWR_VR"
SEC"1"
SEC_TYPE"0402LF";
"A"
$PN"1"46;
"B"
$PN"2"21;
%"GND"
"1","(-2000,1100)","0","mstr_symbols","I91";
;
HDL_POWER"GND"
BODY_TYPE"PLUMBING"
CDS_LIB"mstr_symbols"
ROOM"VDDQ_KLM_PWR_VR"
VOLTAGE"0"
SIZE"1B";
"A\NAC"21;
%"GND"
"1","(-2075,375)","0","mstr_symbols","I93";
;
CDS_LIB"mstr_symbols"
SIZE"1B"
VOLTAGE"0"
BOM_COST"PROC_VRD_VCCIN_CPU0"
ROOM"PVCCIN_CPU0_PWR_VR"
BODY_TYPE"PLUMBING"
HDL_POWER"GND";
"A\NAC"48;
END.
